(kicad_pcb
	(version 20260206)
	(generator "pcbnew")
	(generator_version "10.0")
	(general
		(thickness 1.6)
		(legacy_teardrops no)
	)
	(paper "A4")
	(title_block
		(title "12092022_DA0F0TFB6D0_F0T_FAN_BOARD_MP5048_D_brd_v02_OCP.brd")
		(comment 1 "Grand Teton / footprints 736-742 of 924")
	)
	(layers
		(0 "F.Cu" signal "TOP")
		(4 "In1.Cu" signal "GND")
		(6 "In2.Cu" signal "IN1")
		(8 "In3.Cu" signal "IN2")
		(10 "In4.Cu" signal "GND1")
		(2 "B.Cu" signal "BOTTOM")
		(9 "F.Adhes" user "F.Adhesive")
		(11 "B.Adhes" user "B.Adhesive")
		(13 "F.Paste" user "Package Geometry/Pastemask Top")
		(15 "B.Paste" user "Package Geometry/Pastemask Bottom")
		(5 "F.SilkS" user "Ref Des/Silkscreen Top")
		(7 "B.SilkS" user "Ref Des/Silkscreen Bottom")
		(1 "F.Mask" user "Board Geometry/Soldermask Top")
		(3 "B.Mask" user "Board Geometry/Soldermask Bottom")
		(17 "Dwgs.User" user "User.Drawings")
		(19 "Cmts.User" user "User.Comments")
		(21 "Eco1.User" user "User.Eco1")
		(23 "Eco2.User" user "User.Eco2")
		(25 "Edge.Cuts" user "Board Geometry/Outline")
		(27 "Margin" user)
		(31 "F.CrtYd" user "Package Geometry/Place Bound Top")
		(29 "B.CrtYd" user "Package Geometry/Place Bound Bottom")
		(35 "F.Fab" user "Ref Des/Assembly Top")
		(33 "B.Fab" user "Ref Des/Assembly Bottom")
	)
	(footprint ""
		(layer "B.Cu")
		(at 9.779 -249.428 -90)
		(property "Reference" "PR68"
			(at 0 0 90)
			(layer "B.SilkS")
			(hide yes)
			(effects
				(font
					(size 1.27 1.27)
				)
				(justify mirror)
			)
		)
		(property "Value" ""
			(at 0 0 90)
			(layer "B.Fab")
			(effects
				(font
					(size 1.27 1.27)
				)
				(justify mirror)
			)
		)
		(duplicate_pad_numbers_are_jumpers no)
		(fp_line
			(start -0.7874 0.4064)
			(end 0.7874 0.4064)
			(stroke
				(width 0.1524)
				(type default)
			)
			(layer "B.SilkS")
		)
		(fp_line
			(start 0.7874 0.4064)
			(end 0.7874 -0.4064)
			(stroke
				(width 0.1524)
				(type default)
			)
			(layer "B.SilkS")
		)
		(fp_line
			(start -0.7874 -0.4064)
			(end -0.7874 0.4064)
			(stroke
				(width 0.1524)
				(type default)
			)
			(layer "B.SilkS")
		)
		(fp_line
			(start 0.7874 -0.4064)
			(end -0.7874 -0.4064)
			(stroke
				(width 0.1524)
				(type default)
			)
			(layer "B.SilkS")
		)
		(fp_line
			(start -0.67945 0.3048)
			(end -0.120396 0.3048)
			(stroke
				(width 0.1)
				(type default)
			)
			(layer "B.Fab")
		)
		(fp_line
			(start -0.120396 0.3048)
			(end -0.120396 0.2794)
			(stroke
				(width 0.1)
				(type default)
			)
			(layer "B.Fab")
		)
		(fp_line
			(start 0.12065 0.3048)
			(end 0.67945 0.3048)
			(stroke
				(width 0.1)
				(type default)
			)
			(layer "B.Fab")
		)
		(fp_line
			(start 0.67945 0.3048)
			(end 0.67945 -0.305054)
			(stroke
				(width 0.1)
				(type default)
			)
			(layer "B.Fab")
		)
		(fp_line
			(start -0.120396 0.2794)
			(end 0.12065 0.2794)
			(stroke
				(width 0.1)
				(type default)
			)
			(layer "B.Fab")
		)
		(fp_line
			(start 0.12065 0.2794)
			(end 0.12065 0.3048)
			(stroke
				(width 0.1)
				(type default)
			)
			(layer "B.Fab")
		)
		(fp_line
			(start -0.12065 -0.2794)
			(end -0.12065 -0.3048)
			(stroke
				(width 0.1)
				(type default)
			)
			(layer "B.Fab")
		)
		(fp_line
			(start 0.12065 -0.2794)
			(end -0.12065 -0.2794)
			(stroke
				(width 0.1)
				(type default)
			)
			(layer "B.Fab")
		)
		(fp_line
			(start -0.67945 -0.3048)
			(end -0.67945 0.3048)
			(stroke
				(width 0.1)
				(type default)
			)
			(layer "B.Fab")
		)
		(fp_line
			(start -0.12065 -0.3048)
			(end -0.67945 -0.3048)
			(stroke
				(width 0.1)
				(type default)
			)
			(layer "B.Fab")
		)
		(fp_line
			(start 0.12065 -0.305054)
			(end 0.12065 -0.2794)
			(stroke
				(width 0.1)
				(type default)
			)
			(layer "B.Fab")
		)
		(fp_line
			(start 0.67945 -0.305054)
			(end 0.12065 -0.305054)
			(stroke
				(width 0.1)
				(type default)
			)
			(layer "B.Fab")
		)
		(pad "1" smd circle
			(at 0.40005 0 90)
			(size 0 0)
			(layers "B.Cu" "B.Mask" "B.Paste")
			(net "FAN_6_TEMP")
		)
		(pad "2" smd circle
			(at -0.40005 0 90)
			(size 0 0)
			(layers "B.Cu" "B.Mask" "B.Paste")
			(net "GND")
		)
	)
	(footprint ""
		(layer "B.Cu")
		(at 3.81 -252.73 90)
		(property "Reference" "U397"
			(at 2.00533 2.54 0)
			(unlocked yes)
			(layer "B.SilkS")
			(effects
				(font
					(size 0.7874 0.5842)
					(thickness 0.1524)
				)
				(justify left mirror)
			)
		)
		(property "Value" ""
			(at 0 0 90)
			(layer "B.Fab")
			(effects
				(font
					(size 1.27 1.27)
				)
				(justify mirror)
			)
		)
		(duplicate_pad_numbers_are_jumpers no)
		(fp_line
			(start 1.3462 -1.1938)
			(end 1.3462 1.1684)
			(stroke
				(width 0.1524)
				(type default)
			)
			(layer "B.SilkS")
		)
		(fp_line
			(start -1.3462 -1.1938)
			(end 1.3462 -1.1938)
			(stroke
				(width 0.1524)
				(type default)
			)
			(layer "B.SilkS")
		)
		(fp_line
			(start 1.3462 1.1938)
			(end -1.3462 1.1938)
			(stroke
				(width 0.1524)
				(type default)
			)
			(layer "B.SilkS")
		)
		(fp_line
			(start -1.3462 1.1938)
			(end -1.3462 -1.1938)
			(stroke
				(width 0.1524)
				(type default)
			)
			(layer "B.SilkS")
		)
		(fp_poly
			(pts
				(xy 1.418082 -1.288796) (xy 2.059686 -1.502918) (xy 1.63195 -1.930654)
			)
			(stroke
				(width 0)
				(type default)
			)
			(fill yes)
			(layer "B.SilkS")
		)
		(fp_line
			(start 0.674878 -1.124966)
			(end 0.674878 1.124966)
			(stroke
				(width 0.1)
				(type default)
			)
			(layer "B.Fab")
		)
		(fp_line
			(start -0.674878 -1.124966)
			(end 0.674878 -1.124966)
			(stroke
				(width 0.1)
				(type default)
			)
			(layer "B.Fab")
		)
		(fp_line
			(start 0.674878 1.124966)
			(end -0.674878 1.124966)
			(stroke
				(width 0.1)
				(type default)
			)
			(layer "B.Fab")
		)
		(fp_line
			(start -0.674878 1.124966)
			(end -0.674878 -1.124966)
			(stroke
				(width 0.1)
				(type default)
			)
			(layer "B.Fab")
		)
		(fp_poly
			(pts
				(xy 1.447038 -0.760476) (xy 2.052066 -0.457962) (xy 2.052066 -1.06299)
			)
			(stroke
				(width 0)
				(type default)
			)
			(fill yes)
			(layer "B.Fab")
		)
		(pad "1" smd rect
			(at 0.899922 -0.750062 270)
			(size 0.6096 0.6096)
			(layers "B.Cu" "B.Mask" "B.Paste")
			(net "NC_U397_P1")
		)
		(pad "2" smd rect
			(at 0.899922 0 180)
			(size 0.4064 0.6096)
			(layers "B.Cu" "B.Mask" "B.Paste")
			(net "FAN_6_PRSNT_BUF_N")
		)
		(pad "3" smd rect
			(at 0.899922 0.750062 270)
			(size 0.6096 0.6096)
			(layers "B.Cu" "B.Mask" "B.Paste")
			(net "GND")
		)
		(pad "4" smd rect
			(at -0.899922 0.750062 270)
			(size 0.6096 0.6096)
			(layers "B.Cu" "B.Mask" "B.Paste")
			(net "FAN_6_PRESENT")
		)
		(pad "5" smd rect
			(at -0.899922 -0.750062 270)
			(size 0.6096 0.6096)
			(layers "B.Cu" "B.Mask" "B.Paste")
			(net "P3V3_AUX")
		)
	)
	(footprint ""
		(layer "B.Cu")
		(at 18.430494 -258.572 -90)
		(property "Reference" "PR78"
			(at 0 0 90)
			(layer "B.SilkS")
			(hide yes)
			(effects
				(font
					(size 1.27 1.27)
				)
				(justify mirror)
			)
		)
		(property "Value" ""
			(at 0 0 90)
			(layer "B.Fab")
			(effects
				(font
					(size 1.27 1.27)
				)
				(justify mirror)
			)
		)
		(duplicate_pad_numbers_are_jumpers no)
		(fp_line
			(start -0.7874 0.4064)
			(end 0.7874 0.4064)
			(stroke
				(width 0.1524)
				(type default)
			)
			(layer "B.SilkS")
		)
		(fp_line
			(start 0.7874 0.4064)
			(end 0.7874 -0.4064)
			(stroke
				(width 0.1524)
				(type default)
			)
			(layer "B.SilkS")
		)
		(fp_line
			(start -0.7874 -0.4064)
			(end -0.7874 0.4064)
			(stroke
				(width 0.1524)
				(type default)
			)
			(layer "B.SilkS")
		)
		(fp_line
			(start 0.7874 -0.4064)
			(end -0.7874 -0.4064)
			(stroke
				(width 0.1524)
				(type default)
			)
			(layer "B.SilkS")
		)
		(fp_line
			(start -0.67945 0.3048)
			(end -0.120396 0.3048)
			(stroke
				(width 0.1)
				(type default)
			)
			(layer "B.Fab")
		)
		(fp_line
			(start -0.120396 0.3048)
			(end -0.120396 0.2794)
			(stroke
				(width 0.1)
				(type default)
			)
			(layer "B.Fab")
		)
		(fp_line
			(start 0.12065 0.3048)
			(end 0.67945 0.3048)
			(stroke
				(width 0.1)
				(type default)
			)
			(layer "B.Fab")
		)
		(fp_line
			(start 0.67945 0.3048)
			(end 0.67945 -0.305054)
			(stroke
				(width 0.1)
				(type default)
			)
			(layer "B.Fab")
		)
		(fp_line
			(start -0.120396 0.2794)
			(end 0.12065 0.2794)
			(stroke
				(width 0.1)
				(type default)
			)
			(layer "B.Fab")
		)
		(fp_line
			(start 0.12065 0.2794)
			(end 0.12065 0.3048)
			(stroke
				(width 0.1)
				(type default)
			)
			(layer "B.Fab")
		)
		(fp_line
			(start -0.12065 -0.2794)
			(end -0.12065 -0.3048)
			(stroke
				(width 0.1)
				(type default)
			)
			(layer "B.Fab")
		)
		(fp_line
			(start 0.12065 -0.2794)
			(end -0.12065 -0.2794)
			(stroke
				(width 0.1)
				(type default)
			)
			(layer "B.Fab")
		)
		(fp_line
			(start -0.67945 -0.3048)
			(end -0.67945 0.3048)
			(stroke
				(width 0.1)
				(type default)
			)
			(layer "B.Fab")
		)
		(fp_line
			(start -0.12065 -0.3048)
			(end -0.67945 -0.3048)
			(stroke
				(width 0.1)
				(type default)
			)
			(layer "B.Fab")
		)
		(fp_line
			(start 0.12065 -0.305054)
			(end 0.12065 -0.2794)
			(stroke
				(width 0.1)
				(type default)
			)
			(layer "B.Fab")
		)
		(fp_line
			(start 0.67945 -0.305054)
			(end 0.12065 -0.305054)
			(stroke
				(width 0.1)
				(type default)
			)
			(layer "B.Fab")
		)
		(pad "1" smd circle
			(at 0.40005 0 90)
			(size 0 0)
			(layers "B.Cu" "B.Mask" "B.Paste")
			(net "GND")
		)
		(pad "2" smd circle
			(at -0.40005 0 90)
			(size 0 0)
			(layers "B.Cu" "B.Mask" "B.Paste")
			(net "FAN_7_IMON")
		)
	)
	(footprint ""
		(layer "B.Cu")
		(at 17.653 -130.81 180)
		(property "Reference" "R5438"
			(at 0 0 0)
			(layer "B.SilkS")
			(hide yes)
			(effects
				(font
					(size 1.27 1.27)
				)
				(justify mirror)
			)
		)
		(property "Value" ""
			(at 0 0 0)
			(layer "B.Fab")
			(effects
				(font
					(size 1.27 1.27)
				)
				(justify mirror)
			)
		)
		(duplicate_pad_numbers_are_jumpers no)
		(fp_line
			(start 0.7874 0.4064)
			(end 0.7874 -0.4064)
			(stroke
				(width 0.1524)
				(type default)
			)
			(layer "B.SilkS")
		)
		(fp_line
			(start 0.7874 -0.4064)
			(end -0.7874 -0.4064)
			(stroke
				(width 0.1524)
				(type default)
			)
			(layer "B.SilkS")
		)
		(fp_line
			(start -0.7874 0.4064)
			(end 0.7874 0.4064)
			(stroke
				(width 0.1524)
				(type default)
			)
			(layer "B.SilkS")
		)
		(fp_line
			(start -0.7874 -0.4064)
			(end -0.7874 0.4064)
			(stroke
				(width 0.1524)
				(type default)
			)
			(layer "B.SilkS")
		)
		(fp_line
			(start 0.67945 0.3048)
			(end 0.67945 -0.305054)
			(stroke
				(width 0.1)
				(type default)
			)
			(layer "B.Fab")
		)
		(fp_line
			(start 0.67945 -0.305054)
			(end 0.12065 -0.305054)
			(stroke
				(width 0.1)
				(type default)
			)
			(layer "B.Fab")
		)
		(fp_line
			(start 0.12065 0.3048)
			(end 0.67945 0.3048)
			(stroke
				(width 0.1)
				(type default)
			)
			(layer "B.Fab")
		)
		(fp_line
			(start 0.12065 0.2794)
			(end 0.12065 0.3048)
			(stroke
				(width 0.1)
				(type default)
			)
			(layer "B.Fab")
		)
		(fp_line
			(start 0.12065 -0.2794)
			(end -0.12065 -0.2794)
			(stroke
				(width 0.1)
				(type default)
			)
			(layer "B.Fab")
		)
		(fp_line
			(start 0.12065 -0.305054)
			(end 0.12065 -0.2794)
			(stroke
				(width 0.1)
				(type default)
			)
			(layer "B.Fab")
		)
		(fp_line
			(start -0.120396 0.3048)
			(end -0.120396 0.2794)
			(stroke
				(width 0.1)
				(type default)
			)
			(layer "B.Fab")
		)
		(fp_line
			(start -0.120396 0.2794)
			(end 0.12065 0.2794)
			(stroke
				(width 0.1)
				(type default)
			)
			(layer "B.Fab")
		)
		(fp_line
			(start -0.12065 -0.2794)
			(end -0.12065 -0.3048)
			(stroke
				(width 0.1)
				(type default)
			)
			(layer "B.Fab")
		)
		(fp_line
			(start -0.12065 -0.3048)
			(end -0.67945 -0.3048)
			(stroke
				(width 0.1)
				(type default)
			)
			(layer "B.Fab")
		)
		(fp_line
			(start -0.67945 0.3048)
			(end -0.120396 0.3048)
			(stroke
				(width 0.1)
				(type default)
			)
			(layer "B.Fab")
		)
		(fp_line
			(start -0.67945 -0.3048)
			(end -0.67945 0.3048)
			(stroke
				(width 0.1)
				(type default)
			)
			(layer "B.Fab")
		)
		(pad "1" smd rect
			(at 0.40005 0 180)
			(size 0.4572 0.508)
			(layers "B.Cu" "B.Mask" "B.Paste")
			(net "FAN_6_TACH_IL")
		)
		(pad "2" smd rect
			(at -0.40005 0 180)
			(size 0.4572 0.508)
			(layers "B.Cu" "B.Mask" "B.Paste")
			(net "GND")
		)
	)
	(footprint ""
		(layer "B.Cu")
		(at 19.446494 -258.572 90)
		(property "Reference" "PR74"
			(at 0 0 90)
			(layer "B.SilkS")
			(hide yes)
			(effects
				(font
					(size 1.27 1.27)
				)
				(justify mirror)
			)
		)
		(property "Value" ""
			(at 0 0 90)
			(layer "B.Fab")
			(effects
				(font
					(size 1.27 1.27)
				)
				(justify mirror)
			)
		)
		(duplicate_pad_numbers_are_jumpers no)
		(fp_line
			(start 0.7874 -0.4064)
			(end -0.7874 -0.4064)
			(stroke
				(width 0.1524)
				(type default)
			)
			(layer "B.SilkS")
		)
		(fp_line
			(start -0.7874 -0.4064)
			(end -0.7874 0.4064)
			(stroke
				(width 0.1524)
				(type default)
			)
			(layer "B.SilkS")
		)
		(fp_line
			(start 0.7874 0.4064)
			(end 0.7874 -0.4064)
			(stroke
				(width 0.1524)
				(type default)
			)
			(layer "B.SilkS")
		)
		(fp_line
			(start -0.7874 0.4064)
			(end 0.7874 0.4064)
			(stroke
				(width 0.1524)
				(type default)
			)
			(layer "B.SilkS")
		)
		(fp_line
			(start 0.67945 -0.305054)
			(end 0.12065 -0.305054)
			(stroke
				(width 0.1)
				(type default)
			)
			(layer "B.Fab")
		)
		(fp_line
			(start 0.12065 -0.305054)
			(end 0.12065 -0.2794)
			(stroke
				(width 0.1)
				(type default)
			)
			(layer "B.Fab")
		)
		(fp_line
			(start -0.12065 -0.3048)
			(end -0.67945 -0.3048)
			(stroke
				(width 0.1)
				(type default)
			)
			(layer "B.Fab")
		)
		(fp_line
			(start -0.67945 -0.3048)
			(end -0.67945 0.3048)
			(stroke
				(width 0.1)
				(type default)
			)
			(layer "B.Fab")
		)
		(fp_line
			(start 0.12065 -0.2794)
			(end -0.12065 -0.2794)
			(stroke
				(width 0.1)
				(type default)
			)
			(layer "B.Fab")
		)
		(fp_line
			(start -0.12065 -0.2794)
			(end -0.12065 -0.3048)
			(stroke
				(width 0.1)
				(type default)
			)
			(layer "B.Fab")
		)
		(fp_line
			(start 0.12065 0.2794)
			(end 0.12065 0.3048)
			(stroke
				(width 0.1)
				(type default)
			)
			(layer "B.Fab")
		)
		(fp_line
			(start -0.120396 0.2794)
			(end 0.12065 0.2794)
			(stroke
				(width 0.1)
				(type default)
			)
			(layer "B.Fab")
		)
		(fp_line
			(start 0.67945 0.3048)
			(end 0.67945 -0.305054)
			(stroke
				(width 0.1)
				(type default)
			)
			(layer "B.Fab")
		)
		(fp_line
			(start 0.12065 0.3048)
			(end 0.67945 0.3048)
			(stroke
				(width 0.1)
				(type default)
			)
			(layer "B.Fab")
		)
		(fp_line
			(start -0.120396 0.3048)
			(end -0.120396 0.2794)
			(stroke
				(width 0.1)
				(type default)
			)
			(layer "B.Fab")
		)
		(fp_line
			(start -0.67945 0.3048)
			(end -0.120396 0.3048)
			(stroke
				(width 0.1)
				(type default)
			)
			(layer "B.Fab")
		)
		(pad "1" smd circle
			(at 0.40005 0 270)
			(size 0 0)
			(layers "B.Cu" "B.Mask" "B.Paste")
			(net "FAN_7_CS")
		)
		(pad "2" smd circle
			(at -0.40005 0 270)
			(size 0 0)
			(layers "B.Cu" "B.Mask" "B.Paste")
			(net "GND")
		)
	)
	(footprint ""
		(layer "B.Cu")
		(at 33.4518 -273.7104)
		(property "Reference" "C2097"
			(at 0 0 0)
			(layer "B.SilkS")
			(hide yes)
			(effects
				(font
					(size 1.27 1.27)
				)
				(justify mirror)
			)
		)
		(property "Value" ""
			(at 0 0 0)
			(layer "B.Fab")
			(effects
				(font
					(size 1.27 1.27)
				)
				(justify mirror)
			)
		)
		(duplicate_pad_numbers_are_jumpers no)
		(fp_line
			(start -2.2098 -0.9398)
			(end -2.2098 0.9398)
			(stroke
				(width 0.1524)
				(type default)
			)
			(layer "B.SilkS")
		)
		(fp_line
			(start -2.2098 0.9398)
			(end 2.2098 0.9398)
			(stroke
				(width 0.1524)
				(type default)
			)
			(layer "B.SilkS")
		)
		(fp_line
			(start 2.2098 -0.9398)
			(end -2.2098 -0.9398)
			(stroke
				(width 0.1524)
				(type default)
			)
			(layer "B.SilkS")
		)
		(fp_line
			(start 2.2098 0.9398)
			(end 2.2098 -0.9398)
			(stroke
				(width 0.1524)
				(type default)
			)
			(layer "B.SilkS")
		)
		(fp_line
			(start -1.700022 -0.899922)
			(end -1.700022 0.899922)
			(stroke
				(width 0.1)
				(type default)
			)
			(layer "B.Fab")
		)
		(fp_line
			(start -1.700022 0.899922)
			(end 1.700022 0.899922)
			(stroke
				(width 0.1)
				(type default)
			)
			(layer "B.Fab")
		)
		(fp_line
			(start 1.700022 -0.899922)
			(end -1.700022 -0.899922)
			(stroke
				(width 0.1)
				(type default)
			)
			(layer "B.Fab")
		)
		(fp_line
			(start 1.700022 0.899922)
			(end 1.700022 -0.899922)
			(stroke
				(width 0.1)
				(type default)
			)
			(layer "B.Fab")
		)
		(pad "1" smd rect
			(at 1.4732 0)
			(size 1.1684 1.5748)
			(layers "B.Cu" "B.Mask" "B.Paste")
			(net "P52V_FAN_0")
		)
		(pad "2" smd rect
			(at -1.4732 0)
			(size 1.1684 1.5748)
			(layers "B.Cu" "B.Mask" "B.Paste")
			(net "GND")
		)
	)
	(footprint ""
		(layer "B.Cu")
		(at 41.25468 -64.837056 -90)
		(property "Reference" "PR44"
			(at 0 0 90)
			(layer "B.SilkS")
			(hide yes)
			(effects
				(font
					(size 1.27 1.27)
				)
				(justify mirror)
			)
		)
		(property "Value" ""
			(at 0 0 90)
			(layer "B.Fab")
			(effects
				(font
					(size 1.27 1.27)
				)
				(justify mirror)
			)
		)
		(duplicate_pad_numbers_are_jumpers no)
		(fp_line
			(start -0.7874 0.4064)
			(end 0.7874 0.4064)
			(stroke
				(width 0.1524)
				(type default)
			)
			(layer "B.SilkS")
		)
		(fp_line
			(start 0.7874 0.4064)
			(end 0.7874 -0.4064)
			(stroke
				(width 0.1524)
				(type default)
			)
			(layer "B.SilkS")
		)
		(fp_line
			(start -0.7874 -0.4064)
			(end -0.7874 0.4064)
			(stroke
				(width 0.1524)
				(type default)
			)
			(layer "B.SilkS")
		)
		(fp_line
			(start 0.7874 -0.4064)
			(end -0.7874 -0.4064)
			(stroke
				(width 0.1524)
				(type default)
			)
			(layer "B.SilkS")
		)
		(fp_line
			(start -0.67945 0.3048)
			(end -0.120396 0.3048)
			(stroke
				(width 0.1)
				(type default)
			)
			(layer "B.Fab")
		)
		(fp_line
			(start -0.120396 0.3048)
			(end -0.120396 0.2794)
			(stroke
				(width 0.1)
				(type default)
			)
			(layer "B.Fab")
		)
		(fp_line
			(start 0.12065 0.3048)
			(end 0.67945 0.3048)
			(stroke
				(width 0.1)
				(type default)
			)
			(layer "B.Fab")
		)
		(fp_line
			(start 0.67945 0.3048)
			(end 0.67945 -0.305054)
			(stroke
				(width 0.1)
				(type default)
			)
			(layer "B.Fab")
		)
		(fp_line
			(start -0.120396 0.2794)
			(end 0.12065 0.2794)
			(stroke
				(width 0.1)
				(type default)
			)
			(layer "B.Fab")
		)
		(fp_line
			(start 0.12065 0.2794)
			(end 0.12065 0.3048)
			(stroke
				(width 0.1)
				(type default)
			)
			(layer "B.Fab")
		)
		(fp_line
			(start -0.12065 -0.2794)
			(end -0.12065 -0.3048)
			(stroke
				(width 0.1)
				(type default)
			)
			(layer "B.Fab")
		)
		(fp_line
			(start 0.12065 -0.2794)
			(end -0.12065 -0.2794)
			(stroke
				(width 0.1)
				(type default)
			)
			(layer "B.Fab")
		)
		(fp_line
			(start -0.67945 -0.3048)
			(end -0.67945 0.3048)
			(stroke
				(width 0.1)
				(type default)
			)
			(layer "B.Fab")
		)
		(fp_line
			(start -0.12065 -0.3048)
			(end -0.67945 -0.3048)
			(stroke
				(width 0.1)
				(type default)
			)
			(layer "B.Fab")
		)
		(fp_line
			(start 0.12065 -0.305054)
			(end 0.12065 -0.2794)
			(stroke
				(width 0.1)
				(type default)
			)
			(layer "B.Fab")
		)
		(fp_line
			(start 0.67945 -0.305054)
			(end 0.12065 -0.305054)
			(stroke
				(width 0.1)
				(type default)
			)
			(layer "B.Fab")
		)
		(pad "1" smd circle
			(at 0.40005 0 90)
			(size 0 0)
			(layers "B.Cu" "B.Mask" "B.Paste")
			(net "FAN_3_TEMP")
		)
		(pad "2" smd circle
			(at -0.40005 0 90)
			(size 0 0)
			(layers "B.Cu" "B.Mask" "B.Paste")
			(net "GND")
		)
	)
)
